FILE_TYPE = MACRO_DRAWING;
SET COLOR_WIRE YELLOW;
SET COLOR_PROP ORANGE;
SET COLOR_DOT WHITE;
SET COLOR_ARC YELLOW;
SET COLOR_BODY GREEN;
SET COLOR_NOTE PURPLE;
SET PROP_DISPLAY VALUE;
SET PAGE_NUMBER P172;
FORCEADD Q_RES..2
(-7300 3900);
FORCEPROP 1 LAST PART_NUMBER CS11132FB02
J 0
(-7260 3775);
DISPLAY 0.787234 (-7260 3775);
DISPLAY INVISIBLE (-7260 3775);
FORCEPROP 1 LAST PACK_TYPE 0402LF
J 0
(-7260 3725);
DISPLAY 0.787234 (-7260 3725);
FORCEPROP 1 LAST VALUE 113
J 0
(-7255 3975);
DISPLAY 0.978723 (-7255 3975);
FORCEPROP 1 LAST TOLERANCE 1%
J 0
(-7255 3925);
DISPLAY 0.978723 (-7255 3925);
FORCEPROP 1 LAST WATTAGE 1/16W
J 0
(-7260 3875);
DISPLAY 0.787234 (-7260 3875);
FORCEPROP 1 LAST MATERIAL CHIP
J 0
(-7260 3825);
DISPLAY 0.787234 (-7260 3825);
FORCEPROP 1 LAST $LOCATION R496
J 0
(-7255 4025);
DISPLAY 0.978723 (-7255 4025);
FORCEPROP 1 LASTPIN (-7300 4000) $PN 1
J 0
(-7295 3962);
DISPLAY 0.787234 (-7295 3962);
FORCEPROP 1 LASTPIN (-7300 3800) $PN 2
J 0
(-7295 3810);
DISPLAY 0.787234 (-7295 3810);
FORCEPROP 1 LAST PATH I10
J 0
(-7250 4075);
DISPLAY 0.978723 (-7250 4075);
PAINT WHITE (-7250 4075);
DISPLAY INVISIBLE (-7250 4075);
FORCEPROP 2 LAST CDS_LIB pure_quanta
J 2
(-7300 3900);
PAINT MONO (-7300 3900);
DISPLAY INVISIBLE (-7300 3900);
FORCEPROP 2 LAST CDS_LOCATION R496
J 0
(-7250 4125);
DISPLAY 1.021277 (-7250 4125);
DISPLAY INVISIBLE (-7250 4125);
FORCEPROP 2 LAST $SEC 1
J 0
(-7250 4125);
DISPLAY 0.680851 (-7250 4125);
PAINT MONO (-7250 4125);
DISPLAY INVISIBLE (-7250 4125);
FORCEPROP 2 LAST CDS_SEC 1
J 0
(-7250 4125);
DISPLAY 1.021277 (-7250 4125);
DISPLAY INVISIBLE (-7250 4125);
FORCEADD EMMITSBURG_REV0P9..2
(-4125 3500);
FORCEPROP 1 LAST PART_NUMBER AJ0QV2N0T00
J 0
(-4672 4464);
DISPLAY 0.723404 (-4672 4464);
PAINT GREEN (-4672 4464);
DISPLAY INVISIBLE (-4672 4464);
FORCEPROP 1 LAST MATERIAL IC
J 0
(-4672 4337);
DISPLAY 0.723404 (-4672 4337);
PAINT GREEN (-4672 4337);
FORCEPROP 2 LAST VALUE GFNOCPU04302300-QV2N-MM#99A1WT
J 0
(-4650 4650);
DISPLAY 1.021277 (-4650 4650);
FORCEPROP 2 LAST PART_TYPE SMLF
J 0
(-4650 4700);
DISPLAY 1.021277 (-4650 4700);
FORCEPROP 1 LAST $LOCATION U4
J 0
(-4672 4611);
DISPLAY 0.723404 (-4672 4611);
PAINT GREEN (-4672 4611);
FORCEPROP 2 LASTPIN (-4825 4125) $PN BC40
J 2
(-4835 4135);
DISPLAY 0.808511 (-4835 4135);
FORCEPROP 2 LASTPIN (-4825 4175) $PN BB41
J 2
(-4835 4185);
DISPLAY 0.808511 (-4835 4185);
FORCEPROP 2 LASTPIN (-3425 2825) $PN AR42
J 0
(-3415 2835);
DISPLAY 0.808511 (-3415 2835);
FORCEPROP 2 LASTPIN (-3425 2925) $PN AP43
J 0
(-3415 2935);
DISPLAY 0.808511 (-3415 2935);
FORCEPROP 2 LASTPIN (-3425 3025) $PN AT43
J 0
(-3415 3035);
DISPLAY 0.808511 (-3415 3035);
FORCEPROP 2 LASTPIN (-3425 3125) $PN AN42
J 0
(-3415 3135);
DISPLAY 0.808511 (-3415 3135);
FORCEPROP 2 LASTPIN (-3425 3225) $PN AU42
J 0
(-3415 3235);
DISPLAY 0.808511 (-3415 3235);
FORCEPROP 2 LASTPIN (-3425 3325) $PN AL43
J 0
(-3415 3335);
DISPLAY 0.808511 (-3415 3335);
FORCEPROP 2 LASTPIN (-3425 3425) $PN AV43
J 0
(-3415 3435);
DISPLAY 0.808511 (-3415 3435);
FORCEPROP 2 LASTPIN (-3425 3525) $PN AK42
J 0
(-3415 3535);
DISPLAY 0.808511 (-3415 3535);
FORCEPROP 2 LASTPIN (-3425 3625) $PN AW42
J 0
(-3415 3635);
DISPLAY 0.808511 (-3415 3635);
FORCEPROP 2 LASTPIN (-3425 3725) $PN AJ43
J 0
(-3415 3735);
DISPLAY 0.808511 (-3415 3735);
FORCEPROP 2 LASTPIN (-3425 3825) $PN AY43
J 0
(-3415 3835);
DISPLAY 0.808511 (-3415 3835);
FORCEPROP 2 LASTPIN (-3425 3925) $PN AH42
J 0
(-3415 3935);
DISPLAY 0.808511 (-3415 3935);
FORCEPROP 2 LASTPIN (-3425 4025) $PN BA42
J 0
(-3415 4035);
DISPLAY 0.808511 (-3415 4035);
FORCEPROP 2 LASTPIN (-3425 4125) $PN AG43
J 0
(-3415 4135);
DISPLAY 0.808511 (-3415 4135);
FORCEPROP 2 LASTPIN (-3425 2875) $PN AR40
J 0
(-3415 2885);
DISPLAY 0.808511 (-3415 2885);
FORCEPROP 2 LASTPIN (-3425 2975) $PN AP41
J 0
(-3415 2985);
DISPLAY 0.808511 (-3415 2985);
FORCEPROP 2 LASTPIN (-3425 3075) $PN AT41
J 0
(-3415 3085);
DISPLAY 0.808511 (-3415 3085);
FORCEPROP 2 LASTPIN (-3425 3175) $PN AN40
J 0
(-3415 3185);
DISPLAY 0.808511 (-3415 3185);
FORCEPROP 2 LASTPIN (-3425 3275) $PN AU40
J 0
(-3415 3285);
DISPLAY 0.808511 (-3415 3285);
FORCEPROP 2 LASTPIN (-3425 3375) $PN AL41
J 0
(-3415 3385);
DISPLAY 0.808511 (-3415 3385);
FORCEPROP 2 LASTPIN (-3425 3475) $PN AV41
J 0
(-3415 3485);
DISPLAY 0.808511 (-3415 3485);
FORCEPROP 2 LASTPIN (-3425 3575) $PN AK40
J 0
(-3415 3585);
DISPLAY 0.808511 (-3415 3585);
FORCEPROP 2 LASTPIN (-3425 3675) $PN AW40
J 0
(-3415 3685);
DISPLAY 0.808511 (-3415 3685);
FORCEPROP 2 LASTPIN (-3425 3775) $PN AJ41
J 0
(-3415 3785);
DISPLAY 0.808511 (-3415 3785);
FORCEPROP 2 LASTPIN (-3425 3875) $PN AY41
J 0
(-3415 3885);
DISPLAY 0.808511 (-3415 3885);
FORCEPROP 2 LASTPIN (-3425 3975) $PN AH40
J 0
(-3415 3985);
DISPLAY 0.808511 (-3415 3985);
FORCEPROP 2 LASTPIN (-3425 4075) $PN BA40
J 0
(-3415 4085);
DISPLAY 0.808511 (-3415 4085);
FORCEPROP 2 LASTPIN (-3425 4175) $PN AG41
J 0
(-3415 4185);
DISPLAY 0.808511 (-3415 4185);
FORCEPROP 2 LAST CDS_LIB pure_quanta
J 0
(-4125 3500);
PAINT MONO (-4125 3500);
DISPLAY INVISIBLE (-4125 3500);
FORCEPROP 1 LAST CDS_LMAN_SYM_OUTLINE -550,825,550,-825
J 0
(-4125 3500);
DISPLAY 0.468085 (-4125 3500);
PAINT GREEN (-4125 3500);
DISPLAY INVISIBLE (-4125 3500);
FORCEPROP 1 LAST NEEDS_NO_SIZE TRUE
J 0
(-4125 3500);
DISPLAY 0.723404 (-4125 3500);
PAINT GREEN (-4125 3500);
DISPLAY INVISIBLE (-4125 3500);
FORCEPROP 1 LAST PATH I11
J 0
(-4125 3500);
DISPLAY 0.723404 (-4125 3500);
PAINT GREEN (-4125 3500);
DISPLAY INVISIBLE (-4125 3500);
FORCEPROP 2 LAST CDS_LOCATION U4
J 0
(-4675 4500);
DISPLAY 1.021277 (-4675 4500);
DISPLAY INVISIBLE (-4675 4500);
FORCEPROP 2 LAST $SEC 2
J 0
(-4650 4750);
DISPLAY 0.680851 (-4650 4750);
PAINT MONO (-4650 4750);
DISPLAY INVISIBLE (-4650 4750);
FORCEPROP 2 LAST CDS_SEC 2
J 0
(-4675 4500);
DISPLAY 1.021277 (-4675 4500);
DISPLAY INVISIBLE (-4675 4500);
FORCEADD OFFPAGE..3
(-2175 2825);
FORCEPROP 2 LAST $XR0 196 
J 0
(-1961 2825);
DISPLAY 0.638298 (-1961 2825);
PAINT MONO (-1961 2825);
FORCEPROP 2 LAST CDS_LIB standard
J 0
(-2175 2825);
DISPLAY INVISIBLE (-2175 2825);
FORCEPROP 2 LAST PATH I12
J 0
(-1975 2900);
DISPLAY 1.021277 (-1975 2900);
DISPLAY INVISIBLE (-1975 2900);
FORCEPROP 1 LAST COMMENT_BODY TRUE
J 0
(-2225 2725);
DISPLAY 0.872340 (-2225 2725);
PAINT GREEN (-2225 2725);
DISPLAY INVISIBLE (-2225 2725);
FORCEPROP 1 LAST OFFPAGE TRUE
J 0
(-1850 2700);
DISPLAY 0.872340 (-1850 2700);
PAINT GREEN (-1850 2700);
DISPLAY INVISIBLE (-1850 2700);
FORCEADD OFFPAGE..3
(-2175 2875);
FORCEPROP 2 LAST $XR0 196 
J 0
(-1961 2875);
DISPLAY 0.638298 (-1961 2875);
PAINT MONO (-1961 2875);
FORCEPROP 2 LAST CDS_LIB standard
J 0
(-2175 2875);
DISPLAY INVISIBLE (-2175 2875);
FORCEPROP 2 LAST PATH I13
J 0
(-1975 2950);
DISPLAY 1.021277 (-1975 2950);
DISPLAY INVISIBLE (-1975 2950);
FORCEPROP 1 LAST COMMENT_BODY TRUE
J 0
(-2225 2775);
DISPLAY 0.872340 (-2225 2775);
PAINT GREEN (-2225 2775);
DISPLAY INVISIBLE (-2225 2775);
FORCEPROP 1 LAST OFFPAGE TRUE
J 0
(-1850 2750);
DISPLAY 0.872340 (-1850 2750);
PAINT GREEN (-1850 2750);
DISPLAY INVISIBLE (-1850 2750);
FORCEADD OFFPAGE..3
(-2175 3125);
FORCEPROP 2 LAST $XR0 153 
J 0
(-1961 3125);
DISPLAY 0.638298 (-1961 3125);
PAINT MONO (-1961 3125);
FORCEPROP 2 LAST CDS_LIB standard
J 0
(-2175 3125);
PAINT MONO (-2175 3125);
DISPLAY INVISIBLE (-2175 3125);
FORCEPROP 2 LAST PATH I20
J 0
(-1950 3175);
DISPLAY 1.021277 (-1950 3175);
DISPLAY INVISIBLE (-1950 3175);
FORCEPROP 1 LAST OFFPAGE TRUE
J 0
(-1850 3000);
DISPLAY 0.872340 (-1850 3000);
PAINT GREEN (-1850 3000);
DISPLAY INVISIBLE (-1850 3000);
FORCEPROP 1 LAST COMMENT_BODY TRUE
J 0
(-2225 3025);
DISPLAY 0.872340 (-2225 3025);
PAINT GREEN (-2225 3025);
DISPLAY INVISIBLE (-2225 3025);
FORCEADD OFFPAGE..3
(-2175 3175);
FORCEPROP 2 LAST $XR0 153 
J 0
(-1961 3175);
DISPLAY 0.638298 (-1961 3175);
PAINT MONO (-1961 3175);
FORCEPROP 2 LAST CDS_LIB standard
J 0
(-2175 3175);
PAINT MONO (-2175 3175);
DISPLAY INVISIBLE (-2175 3175);
FORCEPROP 2 LAST PATH I21
J 0
(-1950 3225);
DISPLAY 1.021277 (-1950 3225);
DISPLAY INVISIBLE (-1950 3225);
FORCEPROP 1 LAST OFFPAGE TRUE
J 0
(-1850 3050);
DISPLAY 0.872340 (-1850 3050);
PAINT GREEN (-1850 3050);
DISPLAY INVISIBLE (-1850 3050);
FORCEPROP 1 LAST COMMENT_BODY TRUE
J 0
(-2225 3075);
DISPLAY 0.872340 (-2225 3075);
PAINT GREEN (-2225 3075);
DISPLAY INVISIBLE (-2225 3075);
FORCEADD OFFPAGE..3
(-2175 3675);
FORCEPROP 2 LAST $XR0 240 
J 0
(-1961 3675);
DISPLAY 0.638298 (-1961 3675);
PAINT MONO (-1961 3675);
FORCEPROP 1 LAST COMMENT_BODY TRUE
J 0
(-2225 3575);
DISPLAY 0.872340 (-2225 3575);
PAINT GREEN (-2225 3575);
DISPLAY INVISIBLE (-2225 3575);
FORCEPROP 1 LAST OFFPAGE TRUE
J 0
(-1850 3550);
DISPLAY 0.872340 (-1850 3550);
PAINT GREEN (-1850 3550);
DISPLAY INVISIBLE (-1850 3550);
FORCEPROP 2 LAST PATH I24
J 0
(-1950 3725);
DISPLAY 1.021277 (-1950 3725);
DISPLAY INVISIBLE (-1950 3725);
FORCEPROP 2 LAST CDS_LIB standard
J 0
(-2175 3675);
PAINT MONO (-2175 3675);
DISPLAY INVISIBLE (-2175 3675);
FORCEADD OFFPAGE..3
(-2175 3625);
FORCEPROP 2 LAST $XR0 240 
J 0
(-1961 3625);
DISPLAY 0.638298 (-1961 3625);
PAINT MONO (-1961 3625);
FORCEPROP 1 LAST COMMENT_BODY TRUE
J 0
(-2225 3525);
DISPLAY 0.872340 (-2225 3525);
PAINT GREEN (-2225 3525);
DISPLAY INVISIBLE (-2225 3525);
FORCEPROP 1 LAST OFFPAGE TRUE
J 0
(-1850 3500);
DISPLAY 0.872340 (-1850 3500);
PAINT GREEN (-1850 3500);
DISPLAY INVISIBLE (-1850 3500);
FORCEPROP 2 LAST PATH I25
J 0
(-1950 3675);
DISPLAY 1.021277 (-1950 3675);
DISPLAY INVISIBLE (-1950 3675);
FORCEPROP 2 LAST CDS_LIB standard
J 0
(-2175 3625);
PAINT MONO (-2175 3625);
DISPLAY INVISIBLE (-2175 3625);
FORCEADD OFFPAGE..3
(-2175 3325);
FORCEPROP 2 LAST $XR0 159 
J 0
(-1961 3325);
DISPLAY 0.638298 (-1961 3325);
PAINT MONO (-1961 3325);
FORCEPROP 2 LAST PATH I32
J 0
(-1950 3375);
DISPLAY 1.021277 (-1950 3375);
DISPLAY INVISIBLE (-1950 3375);
FORCEPROP 2 LAST CDS_LIB standard
J 0
(-2175 3325);
PAINT MONO (-2175 3325);
DISPLAY INVISIBLE (-2175 3325);
FORCEPROP 1 LAST COMMENT_BODY TRUE
J 0
(-2225 3225);
DISPLAY 0.872340 (-2225 3225);
PAINT GREEN (-2225 3225);
DISPLAY INVISIBLE (-2225 3225);
FORCEPROP 1 LAST OFFPAGE TRUE
J 0
(-1850 3200);
DISPLAY 0.872340 (-1850 3200);
PAINT GREEN (-1850 3200);
DISPLAY INVISIBLE (-1850 3200);
FORCEADD OFFPAGE..3
(-2175 3375);
FORCEPROP 2 LAST $XR0 159 
J 0
(-1961 3375);
DISPLAY 0.638298 (-1961 3375);
PAINT MONO (-1961 3375);
FORCEPROP 2 LAST PATH I33
J 0
(-1950 3425);
DISPLAY 1.021277 (-1950 3425);
DISPLAY INVISIBLE (-1950 3425);
FORCEPROP 2 LAST CDS_LIB standard
J 0
(-2175 3375);
PAINT MONO (-2175 3375);
DISPLAY INVISIBLE (-2175 3375);
FORCEPROP 1 LAST COMMENT_BODY TRUE
J 0
(-2225 3275);
DISPLAY 0.872340 (-2225 3275);
PAINT GREEN (-2225 3275);
DISPLAY INVISIBLE (-2225 3275);
FORCEPROP 1 LAST OFFPAGE TRUE
J 0
(-1850 3250);
DISPLAY 0.872340 (-1850 3250);
PAINT GREEN (-1850 3250);
DISPLAY INVISIBLE (-1850 3250);
FORCEADD OFFPAGE..3
(-2175 3525);
FORCEPROP 2 LAST $XR0 240 
J 0
(-1961 3525);
DISPLAY 0.638298 (-1961 3525);
PAINT MONO (-1961 3525);
FORCEPROP 2 LAST CDS_LIB standard
J 0
(-2175 3525);
DISPLAY INVISIBLE (-2175 3525);
FORCEPROP 2 LAST PATH I34
J 0
(-1950 3575);
DISPLAY 1.021277 (-1950 3575);
DISPLAY INVISIBLE (-1950 3575);
FORCEPROP 1 LAST OFFPAGE TRUE
J 0
(-1850 3400);
DISPLAY 0.872340 (-1850 3400);
PAINT GREEN (-1850 3400);
DISPLAY INVISIBLE (-1850 3400);
FORCEPROP 1 LAST COMMENT_BODY TRUE
J 0
(-2225 3425);
DISPLAY 0.872340 (-2225 3425);
PAINT GREEN (-2225 3425);
DISPLAY INVISIBLE (-2225 3425);
FORCEADD OFFPAGE..3
(-2175 3575);
FORCEPROP 2 LAST $XR0 240 
J 0
(-1961 3575);
DISPLAY 0.638298 (-1961 3575);
PAINT MONO (-1961 3575);
FORCEPROP 2 LAST CDS_LIB standard
J 0
(-2175 3575);
DISPLAY INVISIBLE (-2175 3575);
FORCEPROP 2 LAST PATH I35
J 0
(-1950 3625);
DISPLAY 1.021277 (-1950 3625);
DISPLAY INVISIBLE (-1950 3625);
FORCEPROP 1 LAST OFFPAGE TRUE
J 0
(-1850 3450);
DISPLAY 0.872340 (-1850 3450);
PAINT GREEN (-1850 3450);
DISPLAY INVISIBLE (-1850 3450);
FORCEPROP 1 LAST COMMENT_BODY TRUE
J 0
(-2225 3475);
DISPLAY 0.872340 (-2225 3475);
PAINT GREEN (-2225 3475);
DISPLAY INVISIBLE (-2225 3475);
FORCEADD UNIVERSAL_GND..1
(-7300 3625);
FORCEPROP 3 LASTPIN (-7300 3675) SIG_NAME GND\g
J 0
(-7290 3685);
DISPLAY 0.659574 (-7290 3685);
PAINT MONO (-7290 3685);
DISPLAY INVISIBLE (-7290 3685);
FORCEPROP 1 LAST HDL_POWER GND
J 1
(-7275 3550);
DISPLAY 0.872340 (-7275 3550);
PAINT GREEN (-7275 3550);
DISPLAY INVISIBLE (-7275 3550);
FORCEPROP 2 LAST CDS_LIB logical_power
J 0
(-7300 3625);
DISPLAY INVISIBLE (-7300 3625);
FORCEPROP 1 LAST PATH I9
J 0
(-7225 3625);
DISPLAY 0.872340 (-7225 3625);
PAINT AQUA (-7225 3625);
DISPLAY INVISIBLE (-7225 3625);
FORCEADD DESIGN_NOTE..1
(-5900 4625);
FORCEPROP 0 LAST L1 PIN BT69 & BP69 ARE VSS IN V1.0
J 0
(-6100 4475);
DISPLAY 0.851064 (-6100 4475);
PAINT WHITE (-6100 4475);
FORCEPROP 2 LAST CDS_LIB logical_power
J 0
(-5900 4625);
DISPLAY INVISIBLE (-5900 4625);
FORCEPROP 1 LAST COMMENT_BODY TRUE
J 0
(-5875 4725);
DISPLAY 0.978723 (-5875 4725);
DISPLAY INVISIBLE (-5875 4725);
FORCEADD DESIGN_NOTE..1
(-1725 1700);
FORCEPROP 2 LAST CDS_LIB logical_power
J 0
(-1725 1700);
DISPLAY INVISIBLE (-1725 1700);
FORCEPROP 1 LAST COMMENT_BODY TRUE
J 0
(-1700 1800);
DISPLAY 0.978723 (-1700 1800);
DISPLAY INVISIBLE (-1700 1800);
FORCEADD CAD_NOTE..1
(-7300 4475);
FORCEPROP 2 LAST CDS_LIB logical_power
J 0
(-7300 4475);
PAINT MONO (-7300 4475);
DISPLAY INVISIBLE (-7300 4475);
FORCEPROP 1 LAST COMMENT_BODY TRUE
J 0
(-7275 4575);
DISPLAY 0.978723 (-7275 4575);
DISPLAY INVISIBLE (-7275 4575);
FORCEADD QUANTA_TITLE_BLOCK_C..1
(1350 -1175);
FORCEPROP 0 LAST CDS_CON_LAST_MODIFIED Fri Aug 25 14:02:52 2023
J 0
(-535 -1160);
PAINT MONO (-535 -1160);
DISPLAY INVISIBLE (-535 -1160);
FORCEPROP 1 LAST CUSTOM_TXT_CDS <CON_LAST_MODIFIED>
J 0
(-535 -1160);
DISPLAY 0.978723 (-535 -1160);
FORCEPROP 2 LAST CUSTOM_TXT_CDS <XR_PAGE_TITLE>
J 0
(-6540 4075);
DISPLAY 0.638298 (-6540 4075);
PAINT PINK (-6540 4075);
DISPLAY INVISIBLE (-6540 4075);
FORCEPROP 2 LAST CUSTOM_TXT_CDS <Q_PROJ>
J 0
(-1032 -1073);
DISPLAY 1.212766 (-1032 -1073);
FORCEPROP 2 LAST CUSTOM_TXT_CDS <Q_REV>
J 0
(1166 -1072);
DISPLAY 1.212766 (1166 -1072);
FORCEPROP 2 LAST CUSTOM_TXT_CDS <CON_PAGE_NUM> OF <CON_TOTAL_PAGES>
J 0
(904 -1157);
DISPLAY 0.978723 (904 -1157);
FORCEPROP 2 LAST CUSTOM_TXT_CDS <Q_NUMBER>
J 0
(-53 -1072);
DISPLAY 1.212766 (-53 -1072);
FORCEPROP 2 LAST CUSTOM_TXT_CDS <NAME_1>
J 0
(-1825 -1000);
FORCEPROP 2 LAST CUSTOM_TXT_CDS <NAME_2>
J 0
(-1825 -1125);
FORCEPROP 1 LAST Q_TITLE EMMITSBURG - USB (2/10)
J 0
(-7966 -1149);
DISPLAY 1.957447 (-7966 -1149);
PAINT GREEN (-7966 -1149);
FORCEPROP 1 LAST Q_DEPT 
J 1
(-2413 -1126);
DISPLAY 1.957447 (-2413 -1126);
PAINT GREEN (-2413 -1126);
FORCEPROP 2 LAST CDS_XR_PAGE_TITLE CR-180 : @S9S_MB_2U_LIB.S9S_MB_2U(SCH_1):PAGE180
J 0
(-6540 4075);
DISPLAY 0.638298 (-6540 4075);
PAINT PINK (-6540 4075);
DISPLAY INVISIBLE (-6540 4075);
FORCEPROP 2 LAST CDS_LIB pure_quanta
J 0
(1350 -1175);
PAINT MONO (1350 -1175);
DISPLAY INVISIBLE (1350 -1175);
FORCEPROP 1 LAST CDS_LMAN_SYM_OUTLINE -9475,6775,100,-125
J 0
(1350 -1175);
DISPLAY 0.468085 (1350 -1175);
PAINT GREEN (1350 -1175);
DISPLAY INVISIBLE (1350 -1175);
FORCEPROP 2 LAST PAGE_BORDER TRUE
J 0
(-6540 4075);
DISPLAY 0.638298 (-6540 4075);
PAINT PINK (-6540 4075);
DISPLAY INVISIBLE (-6540 4075);
FORCEPROP 1 LAST COMMENT_BODY TRUE
J 0
(1362 -1188);
DISPLAY 0.978723 (1362 -1188);
PAINT GREEN (1362 -1188);
DISPLAY INVISIBLE (1362 -1188);
WIRE 16 -1 (-7300 3800)(-7300 3675);
WIRE 16 -1 (-2225 3425)(-3425 3425);
FORCEPROP 2 LAST SIG_NAME TP_USB2_6_DN
J 0
(-3185 3435);
DISPLAY 0.851064 (-3185 3435);
PAINT WHITE (-3185 3435);
WIRE 16 -1 (-3425 3375)(-2225 3375);
FORCEPROP 2 LAST SIG_NAME USB2_5_DP
J 0
(-3185 3385);
DISPLAY 0.851064 (-3185 3385);
PAINT WHITE (-3185 3385);
WIRE 16 -1 (-3425 3325)(-2225 3325);
FORCEPROP 2 LAST SIG_NAME USB2_5_DN
J 0
(-3185 3335);
DISPLAY 0.851064 (-3185 3335);
PAINT WHITE (-3185 3335);
WIRE 16 -1 (-3425 3275)(-2225 3275);
FORCEPROP 2 LAST SIG_NAME TP_USB2_4_DP
J 0
(-3185 3285);
DISPLAY 0.851064 (-3185 3285);
PAINT WHITE (-3185 3285);
WIRE 16 -1 (-2225 3925)(-3425 3925);
FORCEPROP 2 LAST SIG_NAME TP_USB2_11_DN
J 0
(-3185 3935);
DISPLAY 0.851064 (-3185 3935);
PAINT WHITE (-3185 3935);
WIRE 16 -1 (-2225 4025)(-3425 4025);
FORCEPROP 2 LAST SIG_NAME TP_USB2_12_DN
J 0
(-3185 4035);
DISPLAY 0.851064 (-3185 4035);
PAINT WHITE (-3185 4035);
WIRE 16 -1 (-2225 4175)(-3425 4175);
FORCEPROP 2 LAST SIG_NAME TP_USB2_13_DP
J 0
(-3185 4185);
DISPLAY 0.851064 (-3185 4185);
PAINT WHITE (-3185 4185);
WIRE 16 -1 (-2225 4125)(-3425 4125);
FORCEPROP 2 LAST SIG_NAME TP_USB2_13_DN
J 0
(-3185 4135);
DISPLAY 0.851064 (-3185 4135);
PAINT WHITE (-3185 4135);
WIRE 16 -1 (-2225 4075)(-3425 4075);
FORCEPROP 2 LAST SIG_NAME TP_USB2_12_DP
J 0
(-3185 4085);
DISPLAY 0.851064 (-3185 4085);
PAINT WHITE (-3185 4085);
WIRE 16 -1 (-2225 3875)(-3425 3875);
FORCEPROP 0 LAST CDS_PHYS_NET_NAME TP_USB2_10_DP
J 0
(-3175 3950);
PAINT MONO (-3175 3950);
DISPLAY INVISIBLE (-3175 3950);
FORCEPROP 2 LAST SIG_NAME TP_USB2_10_DP
J 0
(-3185 3885);
DISPLAY 0.851064 (-3185 3885);
PAINT WHITE (-3185 3885);
WIRE 16 -1 (-2225 3825)(-3425 3825);
FORCEPROP 0 LAST CDS_PHYS_NET_NAME TP_USB2_10_DN
J 0
(-3175 3900);
PAINT MONO (-3175 3900);
DISPLAY INVISIBLE (-3175 3900);
FORCEPROP 2 LAST SIG_NAME TP_USB2_10_DN
J 0
(-3185 3835);
DISPLAY 0.851064 (-3185 3835);
PAINT WHITE (-3185 3835);
WIRE 16 -1 (-2225 3975)(-3425 3975);
FORCEPROP 2 LAST SIG_NAME TP_USB2_11_DP
J 0
(-3185 3985);
DISPLAY 0.851064 (-3185 3985);
PAINT WHITE (-3185 3985);
WIRE 16 -1 (-2225 3775)(-3425 3775);
FORCEPROP 0 LAST CDS_PHYS_NET_NAME TP_USB2_9_DP
J 0
(-3175 3850);
PAINT MONO (-3175 3850);
DISPLAY INVISIBLE (-3175 3850);
FORCEPROP 2 LAST SIG_NAME TP_USB2_9_DP
J 0
(-3185 3785);
DISPLAY 0.851064 (-3185 3785);
PAINT WHITE (-3185 3785);
WIRE 16 -1 (-4825 4125)(-6000 4125);
FORCEPROP 2 LAST SIG_NAME NC_PCH_RSVD<14>
J 0
(-5960 4135);
DISPLAY 0.680851 (-5960 4135);
PAINT WHITE (-5960 4135);
WIRE 16 -1 (-7300 4175)(-7300 4000);
WIRE 16 -1 (-4825 4175)(-7300 4175);
FORCEPROP 2 LAST SIG_NAME PD_PCH_USB2_COMP
J 0
(-5960 4185);
DISPLAY 0.680851 (-5960 4185);
PAINT WHITE (-5960 4185);
WIRE 16 -1 (-200 1575)(-200 1450);
WIRE 16 -1 (-1925 1450)(-1925 1575);
WIRE 16 -1 (-1475 1575)(-1925 1575);
WIRE 16 -1 (-200 1575)(-625 1575);
WIRE 16 -1 (-625 1575)(-625 1450);
WIRE 16 -1 (-200 1450)(-625 1450);
WIRE 16 -1 (-200 1450)(-200 1325);
WIRE 16 -1 (-200 1200)(-200 1325);
WIRE 16 -1 (-200 825)(-200 950);
WIRE 16 -1 (-200 1325)(-625 1325);
WIRE 16 -1 (-625 1450)(-625 1325);
WIRE 16 -1 (-625 1575)(-1050 1575);
WIRE 16 -1 (-1050 1575)(-1475 1575);
WIRE 16 -1 (-625 825)(-200 825);
WIRE 16 -1 (-1925 1325)(-1925 1450);
WIRE 16 -1 (-1475 1450)(-1925 1450);
WIRE 16 -1 (-1475 1575)(-1475 1450);
WIRE 16 -1 (-625 1450)(-1475 1450);
WIRE 16 -1 (-1925 825)(-1475 825);
WIRE 16 -1 (-1925 950)(-1925 825);
WIRE 16 -1 (-1475 1450)(-1475 1325);
WIRE 16 -1 (-1475 1325)(-1925 1325);
WIRE 16 -1 (-1925 1325)(-1925 1200);
WIRE 16 -1 (-1050 825)(-625 825);
WIRE 16 -1 (-1475 825)(-1050 825);
WIRE 16 -1 (-1050 1325)(-1050 1575);
WIRE 16 -1 (-625 1325)(-1050 1325);
WIRE 16 -1 (-1050 1325)(-1475 1325);
WIRE 16 -1 (-200 950)(-200 1075);
WIRE 16 -1 (-200 1200)(-200 1075);
WIRE 16 -1 (-625 1325)(-625 1200);
WIRE 16 -1 (-625 1200)(-200 1200);
WIRE 16 -1 (-625 950)(-625 825);
WIRE 16 -1 (-625 950)(-200 950);
WIRE 16 -1 (-625 1075)(-625 950);
WIRE 16 -1 (-625 1200)(-625 1075);
WIRE 16 -1 (-200 1075)(-625 1075);
WIRE 16 -1 (-1050 1325)(-1050 1200);
WIRE 16 -1 (-1050 1200)(-625 1200);
WIRE 16 -1 (-1050 950)(-1050 825);
WIRE 16 -1 (-1050 950)(-625 950);
WIRE 16 -1 (-1925 1200)(-1475 1200);
WIRE 16 -1 (-1475 1325)(-1475 1200);
WIRE 16 -1 (-1475 1200)(-1050 1200);
WIRE 16 -1 (-1925 1075)(-1925 950);
WIRE 16 -1 (-1925 1075)(-1925 1200);
WIRE 16 -1 (-1925 950)(-1475 950);
WIRE 16 -1 (-1475 825)(-1475 950);
WIRE 16 -1 (-1475 950)(-1050 950);
WIRE 16 -1 (-1475 1075)(-1475 950);
WIRE 16 -1 (-1475 1075)(-1925 1075);
WIRE 16 -1 (-1475 1200)(-1475 1075);
WIRE 16 -1 (-1050 1075)(-1050 950);
WIRE 16 -1 (-1050 1200)(-1050 1075);
WIRE 16 -1 (-625 1075)(-1050 1075);
WIRE 16 -1 (-1050 1075)(-1475 1075);
WIRE 16 -1 (-2225 3525)(-3425 3525);
FORCEPROP 2 LAST SIG_NAME USB2_7_DN
J 0
(-3185 3535);
DISPLAY 0.851064 (-3185 3535);
PAINT WHITE (-3185 3535);
WIRE 16 -1 (-2225 3725)(-3425 3725);
FORCEPROP 0 LAST CDS_PHYS_NET_NAME TP_USB2_9_DN
J 0
(-3175 3800);
PAINT MONO (-3175 3800);
DISPLAY INVISIBLE (-3175 3800);
FORCEPROP 2 LAST SIG_NAME TP_USB2_9_DN
J 0
(-3185 3735);
DISPLAY 0.851064 (-3185 3735);
PAINT WHITE (-3185 3735);
WIRE 16 -1 (-2225 3475)(-3425 3475);
FORCEPROP 2 LAST SIG_NAME TP_USB2_6_DP
J 0
(-3185 3485);
DISPLAY 0.851064 (-3185 3485);
PAINT WHITE (-3185 3485);
WIRE 16 -1 (-2225 3675)(-3425 3675);
FORCEPROP 0 LAST CDS_PHYS_NET_NAME TP_USB2_9_DP
J 0
(-3175 3750);
PAINT MONO (-3175 3750);
DISPLAY INVISIBLE (-3175 3750);
FORCEPROP 2 LAST SIG_NAME USB2_8_DP
J 0
(-3185 3685);
DISPLAY 0.851064 (-3185 3685);
PAINT WHITE (-3185 3685);
WIRE 16 -1 (-2225 3625)(-3425 3625);
FORCEPROP 0 LAST CDS_PHYS_NET_NAME TP_USB2_9_DN
J 0
(-3175 3700);
PAINT MONO (-3175 3700);
DISPLAY INVISIBLE (-3175 3700);
FORCEPROP 2 LAST SIG_NAME USB2_8_DN
J 0
(-3185 3635);
DISPLAY 0.851064 (-3185 3635);
PAINT WHITE (-3185 3635);
WIRE 16 -1 (-2225 3575)(-3425 3575);
FORCEPROP 2 LAST SIG_NAME USB2_7_DP
J 0
(-3185 3585);
DISPLAY 0.851064 (-3185 3585);
PAINT WHITE (-3185 3585);
WIRE 16 -1 (-3425 3225)(-2225 3225);
FORCEPROP 2 LAST SIG_NAME TP_USB2_4_DN
J 0
(-3185 3235);
DISPLAY 0.851064 (-3185 3235);
PAINT WHITE (-3185 3235);
WIRE 16 -1 (-3425 2825)(-2225 2825);
FORCEPROP 2 LAST SIG_NAME USB2_0_DN
J 0
(-3185 2835);
DISPLAY 0.851064 (-3185 2835);
PAINT WHITE (-3185 2835);
WIRE 16 -1 (-3425 3175)(-2225 3175);
FORCEPROP 2 LAST SIG_NAME USB2_3_DP
J 0
(-3185 3185);
DISPLAY 0.851064 (-3185 3185);
PAINT WHITE (-3185 3185);
WIRE 16 -1 (-3425 2975)(-2225 2975);
FORCEPROP 2 LAST SIG_NAME TP_USB2_1_DP
J 0
(-3185 2985);
DISPLAY 0.851064 (-3185 2985);
PAINT WHITE (-3185 2985);
WIRE 16 -1 (-3425 3025)(-2225 3025);
FORCEPROP 2 LAST SIG_NAME TP_USB2_2_DN
J 0
(-3185 3035);
DISPLAY 0.851064 (-3185 3035);
PAINT WHITE (-3185 3035);
WIRE 16 -1 (-3425 3075)(-2225 3075);
FORCEPROP 2 LAST SIG_NAME TP_USB2_2_DP
J 0
(-3185 3085);
DISPLAY 0.851064 (-3185 3085);
PAINT WHITE (-3185 3085);
WIRE 16 -1 (-3425 3125)(-2225 3125);
FORCEPROP 2 LAST SIG_NAME USB2_3_DN
J 0
(-3185 3135);
DISPLAY 0.851064 (-3185 3135);
PAINT WHITE (-3185 3135);
WIRE 16 -1 (-3425 2925)(-2225 2925);
FORCEPROP 2 LAST SIG_NAME TP_USB2_1_DN
J 0
(-3185 2935);
DISPLAY 0.851064 (-3185 2935);
PAINT WHITE (-3185 2935);
WIRE 16 -1 (-3425 2875)(-2225 2875);
FORCEPROP 2 LAST SIG_NAME USB2_0_DP
J 0
(-3185 2885);
DISPLAY 0.851064 (-3185 2885);
PAINT WHITE (-3185 2885);
DOT 1 (-1050 1575);
DOT 1 (-625 1200);
DOT 1 (-1475 1200);
DOT 1 (-1050 825);
DOT 1 (-625 1075);
DOT 1 (-625 1575);
DOT 1 (-1475 1575);
DOT 1 (-200 1450);
DOT 1 (-200 1325);
DOT 1 (-200 1200);
DOT 1 (-200 1075);
DOT 1 (-1925 1075);
DOT 1 (-200 950);
DOT 1 (-1925 950);
DOT 1 (-1050 950);
DOT 1 (-625 950);
DOT 1 (-1475 825);
DOT 1 (-625 1450);
DOT 1 (-625 1325);
DOT 1 (-1475 1325);
DOT 1 (-1475 1450);
DOT 1 (-1925 1450);
DOT 1 (-1475 950);
DOT 1 (-1050 1200);
DOT 1 (-1050 1325);
DOT 1 (-1925 1200);
DOT 1 (-625 825);
DOT 1 (-1475 1075);
DOT 1 (-1925 1325);
DOT 1 (-1050 1075);
FORCENOTE
20210616 MODIFY FOR GT
(-3450 2525) 0;
DISPLAY LEFT (-3450 2525);
DISPLAY 1.595745 (-3450 2525);
PAINT PINK (-3450 2525);
FORCENOTE
 USAGE    USB3.0   USB2.0    OC
(-1875 1475) 0;
DISPLAY LEFT (-1875 1475);
DISPLAY 1.021277 (-1875 1475);
PAINT WHITE (-1875 1475);
FORCENOTE
  SCM     PORT4    PORT0     OC1
(-1875 1350) 0;
DISPLAY LEFT (-1875 1350);
DISPLAY 1.021277 (-1875 1350);
PAINT WHITE (-1875 1350);
FORCENOTE
OCP-SFF     NA     PORT3     NA
(-1850 1250) 0;
DISPLAY LEFT (-1850 1250);
DISPLAY 1.021277 (-1850 1250);
PAINT WHITE (-1850 1250);
FORCENOTE
OCP_V3_2    NA     PORT5     NA
(-1850 1125) 0;
DISPLAY LEFT (-1850 1125);
DISPLAY 1.021277 (-1850 1125);
PAINT WHITE (-1850 1125);
FORCENOTE
 BMC-A      NA     PORT8     NA
(-1850 1000) 0;
DISPLAY LEFT (-1850 1000);
DISPLAY 1.021277 (-1850 1000);
PAINT WHITE (-1850 1000);
FORCENOTE
SCM(RSVD)  PORT5    PORT7     NA
(-1900 875) 0;
DISPLAY LEFT (-1900 875);
DISPLAY 1.021277 (-1900 875);
PAINT WHITE (-1900 875);
FORCENOTE
PLACE IN TOP WITHIN 0.5 INCH
(-7450 4300) 0;
DISPLAY LEFT (-7450 4300);
DISPLAY 1.021277 (-7450 4300);
QUIT
